# T6G (Grand Teton) — schematic netlist excerpt (pin names and nets, part order shuffled) for the footprints in the layout excerpt that follows; sources: Cadence DE-HDL packaged netlist, KiCad conversion of 04192023_DAF0TMB3IC0_F0TG_MB_C_brd_V02_OCP.brd

R1357  Q_RES  2.2K 5% CHIP  pkg 0402LF  page 167 : A = P3V3_AUX ; B = FM_PRSNT_CPU1_N

Q6000  MOSFET_NCH_DUAL  PJT138K IC  pkg SOT363XD  page 254
  S1  = GND
  G1  = PWRGD_P1V2_AUX_R
  D1  = LED_PWRGD_P1V2_AUX_D

C527  Q_CAP  10UF 25V 10% X6S  pkg C0805  page 103 : A = P12V_MEM_CPU1 ; B = GND

(kicad_pcb
	(version 20260206)
	(generator "pcbnew")
	(generator_version "10.0")
	(general
		(thickness 1.6)
		(legacy_teardrops no)
	)
	(paper "A4")
	(title_block
		(title "04192023_DAF0TMB3IC0_F0TG_MB_C_brd_V02_OCP.brd")
		(comment 1 "Grand Teton / footprints 7318-7320 of 8354")
	)
	(layers
		(0 "F.Cu" signal "TOP")
		(4 "In1.Cu" signal "GND")
		(6 "In2.Cu" signal "IN1")
		(8 "In3.Cu" signal "GND1")
		(10 "In4.Cu" signal "IN2")
		(12 "In5.Cu" signal "GND2")
		(14 "In6.Cu" signal "IN3")
		(16 "In7.Cu" signal "GND3")
		(18 "In8.Cu" signal "VCC")
		(20 "In9.Cu" signal "VCC1")
		(22 "In10.Cu" signal "GND4")
		(24 "In11.Cu" signal "IN4")
		(26 "In12.Cu" signal "GND5")
		(28 "In13.Cu" signal "IN5")
		(30 "In14.Cu" signal "GND6")
		(32 "In15.Cu" signal "IN6")
		(34 "In16.Cu" signal "GND7")
		(2 "B.Cu" signal "BOTTOM")
		(9 "F.Adhes" user "F.Adhesive")
		(11 "B.Adhes" user "B.Adhesive")
		(13 "F.Paste" user "Package Geometry/Pastemask Top")
		(15 "B.Paste" user "Package Geometry/Pastemask Bottom")
		(5 "F.SilkS" user "Ref Des/Silkscreen Top")
		(7 "B.SilkS" user "Ref Des/Silkscreen Bottom")
		(1 "F.Mask" user "Board Geometry/Soldermask Top")
		(3 "B.Mask" user "Board Geometry/Soldermask Bottom")
		(17 "Dwgs.User" user "User.Drawings")
		(19 "Cmts.User" user "User.Comments")
		(21 "Eco1.User" user "User.Eco1")
		(23 "Eco2.User" user "User.Eco2")
		(25 "Edge.Cuts" user "Board Geometry/Outline")
		(27 "Margin" user)
		(31 "F.CrtYd" user "Package Geometry/Place Bound Top")
		(29 "B.CrtYd" user "Package Geometry/Place Bound Bottom")
		(35 "F.Fab" user "Ref Des/Assembly Top")
		(33 "B.Fab" user "Ref Des/Assembly Bottom")
	)
	(footprint ""
		(layer "B.Cu")
		(at 428.98695 -33.467548 180)
		(property "Reference" "R1357"
			(at 0 0 0)
			(layer "B.SilkS")
			(hide yes)
			(effects
				(font
					(size 1.27 1.27)
				)
				(justify mirror)
			)
		)
		(property "Value" ""
			(at 0 0 0)
			(layer "B.Fab")
			(effects
				(font
					(size 1.27 1.27)
				)
				(justify mirror)
			)
		)
		(duplicate_pad_numbers_are_jumpers no)
		(fp_line
			(start 0.7874 0.4064)
			(end 0.7874 -0.4064)
			(stroke
				(width 0.1524)
				(type default)
			)
			(layer "B.SilkS")
		)
		(fp_line
			(start 0.7874 -0.4064)
			(end -0.7874 -0.4064)
			(stroke
				(width 0.1524)
				(type default)
			)
			(layer "B.SilkS")
		)
		(fp_line
			(start -0.7874 0.4064)
			(end 0.7874 0.4064)
			(stroke
				(width 0.1524)
				(type default)
			)
			(layer "B.SilkS")
		)
		(fp_line
			(start -0.7874 -0.4064)
			(end -0.7874 0.4064)
			(stroke
				(width 0.1524)
				(type default)
			)
			(layer "B.SilkS")
		)
		(fp_line
			(start 0.67945 0.3048)
			(end 0.67945 -0.305054)
			(stroke
				(width 0.1)
				(type default)
			)
			(layer "B.Fab")
		)
		(fp_line
			(start 0.67945 -0.305054)
			(end 0.12065 -0.305054)
			(stroke
				(width 0.1)
				(type default)
			)
			(layer "B.Fab")
		)
		(fp_line
			(start 0.12065 0.3048)
			(end 0.67945 0.3048)
			(stroke
				(width 0.1)
				(type default)
			)
			(layer "B.Fab")
		)
		(fp_line
			(start 0.12065 0.2794)
			(end 0.12065 0.3048)
			(stroke
				(width 0.1)
				(type default)
			)
			(layer "B.Fab")
		)
		(fp_line
			(start 0.12065 -0.2794)
			(end -0.12065 -0.2794)
			(stroke
				(width 0.1)
				(type default)
			)
			(layer "B.Fab")
		)
		(fp_line
			(start 0.12065 -0.305054)
			(end 0.12065 -0.2794)
			(stroke
				(width 0.1)
				(type default)
			)
			(layer "B.Fab")
		)
		(fp_line
			(start -0.120396 0.3048)
			(end -0.120396 0.2794)
			(stroke
				(width 0.1)
				(type default)
			)
			(layer "B.Fab")
		)
		(fp_line
			(start -0.120396 0.2794)
			(end 0.12065 0.2794)
			(stroke
				(width 0.1)
				(type default)
			)
			(layer "B.Fab")
		)
		(fp_line
			(start -0.12065 -0.2794)
			(end -0.12065 -0.3048)
			(stroke
				(width 0.1)
				(type default)
			)
			(layer "B.Fab")
		)
		(fp_line
			(start -0.12065 -0.3048)
			(end -0.67945 -0.3048)
			(stroke
				(width 0.1)
				(type default)
			)
			(layer "B.Fab")
		)
		(fp_line
			(start -0.67945 0.3048)
			(end -0.120396 0.3048)
			(stroke
				(width 0.1)
				(type default)
			)
			(layer "B.Fab")
		)
		(fp_line
			(start -0.67945 -0.3048)
			(end -0.67945 0.3048)
			(stroke
				(width 0.1)
				(type default)
			)
			(layer "B.Fab")
		)
		(pad "1" smd circle
			(at 0.40005 0)
			(size 0 0)
			(layers "B.Cu" "B.Mask" "B.Paste")
			(net "P3V3_AUX")
		)
		(pad "2" smd circle
			(at -0.40005 0)
			(size 0 0)
			(layers "B.Cu" "B.Mask" "B.Paste")
			(net "FM_PRSNT_CPU1_N")
		)
	)
	(footprint ""
		(layer "B.Cu")
		(at 308.080664 -73.534778)
		(property "Reference" "Q6000"
			(at 1.4224 -1.768348 0)
			(unlocked yes)
			(layer "B.SilkS")
			(effects
				(font
					(size 0.7874 0.5842)
					(thickness 0.1524)
				)
				(justify left mirror)
			)
		)
		(property "Value" ""
			(at 0 0 0)
			(layer "B.Fab")
			(effects
				(font
					(size 1.27 1.27)
				)
				(justify mirror)
			)
		)
		(duplicate_pad_numbers_are_jumpers no)
		(fp_line
			(start -1.332738 -1.100074)
			(end -1.332738 1.100074)
			(stroke
				(width 0.1524)
				(type default)
			)
			(layer "B.SilkS")
		)
		(fp_line
			(start -1.332738 1.100074)
			(end 1.332738 1.100074)
			(stroke
				(width 0.1524)
				(type default)
			)
			(layer "B.SilkS")
		)
		(fp_line
			(start -0.4826 -1.100074)
			(end -1.332738 -1.100074)
			(stroke
				(width 0.1524)
				(type default)
			)
			(layer "B.SilkS")
		)
		(fp_line
			(start 0 -0.541274)
			(end -0.4826 -1.100074)
			(stroke
				(width 0.1524)
				(type default)
			)
			(layer "B.SilkS")
		)
		(fp_line
			(start 0.4826 -1.100074)
			(end 0 -0.541274)
			(stroke
				(width 0.1524)
				(type default)
			)
			(layer "B.SilkS")
		)
		(fp_line
			(start 1.332738 -1.100074)
			(end 0.4826 -1.100074)
			(stroke
				(width 0.1524)
				(type default)
			)
			(layer "B.SilkS")
		)
		(fp_line
			(start 1.332738 1.100074)
			(end 1.332738 -1.100074)
			(stroke
				(width 0.1524)
				(type default)
			)
			(layer "B.SilkS")
		)
		(fp_poly
			(pts
				(xy 1.334516 -0.672084) (xy 2.036572 -1.023112) (xy 2.036572 -0.321056)
			)
			(stroke
				(width 0)
				(type default)
			)
			(fill yes)
			(layer "B.SilkS")
		)
		(fp_line
			(start -0.674878 -1.100074)
			(end -0.674878 1.100074)
			(stroke
				(width 0.1)
				(type default)
			)
			(layer "B.Fab")
		)
		(fp_line
			(start -0.674878 1.100074)
			(end 0.674878 1.100074)
			(stroke
				(width 0.1)
				(type default)
			)
			(layer "B.Fab")
		)
		(fp_line
			(start 0.674878 -1.100074)
			(end -0.674878 -1.100074)
			(stroke
				(width 0.1)
				(type default)
			)
			(layer "B.Fab")
		)
		(fp_line
			(start 0.674878 1.100074)
			(end 0.674878 -1.100074)
			(stroke
				(width 0.1)
				(type default)
			)
			(layer "B.Fab")
		)
		(fp_poly
			(pts
				(xy 2.2352 -0.298958) (xy 2.2352 -1.001014) (xy 1.533144 -0.649986)
			)
			(stroke
				(width 0)
				(type default)
			)
			(fill yes)
			(layer "B.Fab")
		)
		(pad "1" smd rect
			(at 0.94996 -0.649986 90)
			(size 0.4318 0.508)
			(layers "B.Cu" "B.Mask" "B.Paste")
			(net "GND")
		)
		(pad "2" smd rect
			(at 0.94996 0 90)
			(size 0.4318 0.508)
			(layers "B.Cu" "B.Mask" "B.Paste")
			(net "PWRGD_P1V2_AUX_R")
		)
		(pad "3" smd rect
			(at 0.94996 0.649986 90)
			(size 0.4318 0.508)
			(layers "B.Cu" "B.Mask" "B.Paste")
			(net "Net_10797")
		)
		(pad "4" smd rect
			(at -0.94996 0.649986 90)
			(size 0.4318 0.508)
			(layers "B.Cu" "B.Mask" "B.Paste")
			(net "Net_10795")
		)
		(pad "5" smd rect
			(at -0.94996 0 90)
			(size 0.4318 0.508)
			(layers "B.Cu" "B.Mask" "B.Paste")
			(net "Net_10796")
		)
		(pad "6" smd rect
			(at -0.94996 -0.649986 90)
			(size 0.4318 0.508)
			(layers "B.Cu" "B.Mask" "B.Paste")
			(net "LED_PWRGD_P1V2_AUX_D")
		)
	)
	(footprint ""
		(layer "B.Cu")
		(at 21.70811 -192.66027)
		(property "Reference" "C527"
			(at 0 0 0)
			(layer "B.SilkS")
			(hide yes)
			(effects
				(font
					(size 1.27 1.27)
				)
				(justify mirror)
			)
		)
		(property "Value" ""
			(at 0 0 0)
			(layer "B.Fab")
			(effects
				(font
					(size 1.27 1.27)
				)
				(justify mirror)
			)
		)
		(duplicate_pad_numbers_are_jumpers no)
		(fp_line
			(start -1.524 -0.762)
			(end -1.524 0.762)
			(stroke
				(width 0.1524)
				(type default)
			)
			(layer "B.SilkS")
		)
		(fp_line
			(start -1.524 0.762)
			(end 1.524 0.762)
			(stroke
				(width 0.1524)
				(type default)
			)
			(layer "B.SilkS")
		)
		(fp_line
			(start 1.524 -0.762)
			(end -1.524 -0.762)
			(stroke
				(width 0.1524)
				(type default)
			)
			(layer "B.SilkS")
		)
		(fp_line
			(start 1.524 0.762)
			(end 1.524 -0.762)
			(stroke
				(width 0.1524)
				(type default)
			)
			(layer "B.SilkS")
		)
		(fp_line
			(start -1.1049 -0.724916)
			(end 1.1049 -0.724916)
			(stroke
				(width 0.1)
				(type default)
			)
			(layer "B.Fab")
		)
		(fp_line
			(start -1.1049 0.724916)
			(end -1.1049 -0.724916)
			(stroke
				(width 0.1)
				(type default)
			)
			(layer "B.Fab")
		)
		(fp_line
			(start 1.1049 -0.724916)
			(end 1.1049 0.724916)
			(stroke
				(width 0.1)
				(type default)
			)
			(layer "B.Fab")
		)
		(fp_line
			(start 1.1049 0.724916)
			(end -1.1049 0.724916)
			(stroke
				(width 0.1)
				(type default)
			)
			(layer "B.Fab")
		)
		(pad "1" smd rect
			(at 0.889 0)
			(size 1.016 1.27)
			(layers "B.Cu" "B.Mask" "B.Paste")
			(net "P12V_MEM_CPU1")
		)
		(pad "2" smd rect
			(at -0.889 0)
			(size 1.016 1.27)
			(layers "B.Cu" "B.Mask" "B.Paste")
			(net "GND")
		)
	)
)
